# S9S_MB_2U (Grand Teton) — schematic netlist excerpt (pin names and nets, part order shuffled) for the footprints in the layout excerpt that follows; sources: Cadence DE-HDL packaged netlist, KiCad conversion of 03242023_DA0F0TMBIJ0_F0T_Motherboard_J_brd_V01_OCP.brd

R4121  Q_RES  10K 1% CHIP  pkg 0402LF  page 146 : A = P3V3_AUX ; B = PRSNT_CABLE_GPU_B3_N
C554  Q_CAP  0.1UF 25V 10% X7R  pkg 0402  page 221 : A = P3V3_AUX_BMC_D ; B = GND

(kicad_pcb
	(version 20260206)
	(generator "pcbnew")
	(generator_version "10.0")
	(general
		(thickness 1.6)
		(legacy_teardrops no)
	)
	(paper "A4")
	(title_block
		(title "03242023_DA0F0TMBIJ0_F0T_Motherboard_J_brd_V01_OCP.brd")
		(comment 1 "Grand Teton / footprints 4103-4104 of 6105")
	)
	(layers
		(0 "F.Cu" signal "TOP")
		(4 "In1.Cu" signal "GND")
		(6 "In2.Cu" signal "IN1")
		(8 "In3.Cu" signal "GND1")
		(10 "In4.Cu" signal "IN2")
		(12 "In5.Cu" signal "GND2")
		(14 "In6.Cu" signal "IN3")
		(16 "In7.Cu" signal "GND3")
		(18 "In8.Cu" signal "VCC")
		(20 "In9.Cu" signal "VCC1")
		(22 "In10.Cu" signal "GND4")
		(24 "In11.Cu" signal "IN4")
		(26 "In12.Cu" signal "GND5")
		(28 "In13.Cu" signal "IN5")
		(30 "In14.Cu" signal "GND6")
		(32 "In15.Cu" signal "IN6")
		(34 "In16.Cu" signal "GND7")
		(2 "B.Cu" signal "BOTTOM")
		(9 "F.Adhes" user "F.Adhesive")
		(11 "B.Adhes" user "B.Adhesive")
		(13 "F.Paste" user "Package Geometry/Pastemask Top")
		(15 "B.Paste" user "Package Geometry/Pastemask Bottom")
		(5 "F.SilkS" user "Ref Des/Silkscreen Top")
		(7 "B.SilkS" user "Ref Des/Silkscreen Bottom")
		(1 "F.Mask" user "Board Geometry/Soldermask Top")
		(3 "B.Mask" user "Board Geometry/Soldermask Bottom")
		(17 "Dwgs.User" user "User.Drawings")
		(19 "Cmts.User" user "User.Comments")
		(21 "Eco1.User" user "User.Eco1")
		(23 "Eco2.User" user "User.Eco2")
		(25 "Edge.Cuts" user "Board Geometry/Outline")
		(27 "Margin" user)
		(31 "F.CrtYd" user "Package Geometry/Place Bound Top")
		(29 "B.CrtYd" user "Package Geometry/Place Bound Bottom")
		(35 "F.Fab" user "Ref Des/Assembly Top")
		(33 "B.Fab" user "Ref Des/Assembly Bottom")
	)
	(footprint ""
		(layer "F.Cu")
		(at 300.21022 -421.41521 90)
		(property "Reference" "R4121"
			(at 0 0 90)
			(layer "F.SilkS")
			(hide yes)
			(effects
				(font
					(size 1.27 1.27)
				)
			)
		)
		(property "Value" ""
			(at 0 0 90)
			(layer "F.Fab")
			(effects
				(font
					(size 1.27 1.27)
				)
			)
		)
		(duplicate_pad_numbers_are_jumpers no)
		(fp_line
			(start 0.7874 -0.4064)
			(end 0.7874 0.4064)
			(stroke
				(width 0.1524)
				(type default)
			)
			(layer "F.SilkS")
		)
		(fp_line
			(start -0.7874 -0.4064)
			(end 0.7874 -0.4064)
			(stroke
				(width 0.1524)
				(type default)
			)
			(layer "F.SilkS")
		)
		(fp_line
			(start 0.7874 0.4064)
			(end -0.7874 0.4064)
			(stroke
				(width 0.1524)
				(type default)
			)
			(layer "F.SilkS")
		)
		(fp_line
			(start -0.7874 0.4064)
			(end -0.7874 -0.4064)
			(stroke
				(width 0.1524)
				(type default)
			)
			(layer "F.SilkS")
		)
		(fp_line
			(start -0.12065 -0.305054)
			(end -0.12065 -0.2794)
			(stroke
				(width 0.1)
				(type default)
			)
			(layer "F.Fab")
		)
		(fp_line
			(start -0.67945 -0.305054)
			(end -0.12065 -0.305054)
			(stroke
				(width 0.1)
				(type default)
			)
			(layer "F.Fab")
		)
		(fp_line
			(start 0.67945 -0.3048)
			(end 0.67945 0.3048)
			(stroke
				(width 0.1)
				(type default)
			)
			(layer "F.Fab")
		)
		(fp_line
			(start 0.12065 -0.3048)
			(end 0.67945 -0.3048)
			(stroke
				(width 0.1)
				(type default)
			)
			(layer "F.Fab")
		)
		(fp_line
			(start 0.12065 -0.2794)
			(end 0.12065 -0.3048)
			(stroke
				(width 0.1)
				(type default)
			)
			(layer "F.Fab")
		)
		(fp_line
			(start -0.12065 -0.2794)
			(end 0.12065 -0.2794)
			(stroke
				(width 0.1)
				(type default)
			)
			(layer "F.Fab")
		)
		(fp_line
			(start 0.120396 0.2794)
			(end -0.12065 0.2794)
			(stroke
				(width 0.1)
				(type default)
			)
			(layer "F.Fab")
		)
		(fp_line
			(start -0.12065 0.2794)
			(end -0.12065 0.3048)
			(stroke
				(width 0.1)
				(type default)
			)
			(layer "F.Fab")
		)
		(fp_line
			(start 0.67945 0.3048)
			(end 0.120396 0.3048)
			(stroke
				(width 0.1)
				(type default)
			)
			(layer "F.Fab")
		)
		(fp_line
			(start 0.120396 0.3048)
			(end 0.120396 0.2794)
			(stroke
				(width 0.1)
				(type default)
			)
			(layer "F.Fab")
		)
		(fp_line
			(start -0.12065 0.3048)
			(end -0.67945 0.3048)
			(stroke
				(width 0.1)
				(type default)
			)
			(layer "F.Fab")
		)
		(fp_line
			(start -0.67945 0.3048)
			(end -0.67945 -0.305054)
			(stroke
				(width 0.1)
				(type default)
			)
			(layer "F.Fab")
		)
		(pad "1" smd circle
			(at -0.40005 0 90)
			(size 0 0)
			(layers "F.Cu" "F.Mask" "F.Paste")
			(net "P3V3_AUX")
		)
		(pad "2" smd circle
			(at 0.40005 0 90)
			(size 0 0)
			(layers "F.Cu" "F.Mask" "F.Paste")
			(net "PRSNT_CABLE_GPU_B3_N")
		)
	)
	(footprint ""
		(layer "F.Cu")
		(at 133.53288 -74.259948 90)
		(property "Reference" "C554"
			(at 0 0 90)
			(layer "F.SilkS")
			(hide yes)
			(effects
				(font
					(size 1.27 1.27)
				)
			)
		)
		(property "Value" ""
			(at 0 0 90)
			(layer "F.Fab")
			(effects
				(font
					(size 1.27 1.27)
				)
			)
		)
		(duplicate_pad_numbers_are_jumpers no)
		(fp_line
			(start 0.7874 -0.4064)
			(end 0.7874 0.4064)
			(stroke
				(width 0.1524)
				(type default)
			)
			(layer "F.SilkS")
		)
		(fp_line
			(start -0.7874 -0.4064)
			(end 0.7874 -0.4064)
			(stroke
				(width 0.1524)
				(type default)
			)
			(layer "F.SilkS")
		)
		(fp_line
			(start 0.7874 0.4064)
			(end -0.7874 0.4064)
			(stroke
				(width 0.1524)
				(type default)
			)
			(layer "F.SilkS")
		)
		(fp_line
			(start -0.7874 0.4064)
			(end -0.7874 -0.4064)
			(stroke
				(width 0.1524)
				(type default)
			)
			(layer "F.SilkS")
		)
		(fp_line
			(start -0.12065 -0.305054)
			(end -0.12065 -0.2794)
			(stroke
				(width 0.1)
				(type default)
			)
			(layer "F.Fab")
		)
		(fp_line
			(start -0.67945 -0.305054)
			(end -0.12065 -0.305054)
			(stroke
				(width 0.1)
				(type default)
			)
			(layer "F.Fab")
		)
		(fp_line
			(start 0.67945 -0.3048)
			(end 0.67945 0.3048)
			(stroke
				(width 0.1)
				(type default)
			)
			(layer "F.Fab")
		)
		(fp_line
			(start 0.12065 -0.3048)
			(end 0.67945 -0.3048)
			(stroke
				(width 0.1)
				(type default)
			)
			(layer "F.Fab")
		)
		(fp_line
			(start 0.12065 -0.2794)
			(end 0.12065 -0.3048)
			(stroke
				(width 0.1)
				(type default)
			)
			(layer "F.Fab")
		)
		(fp_line
			(start -0.12065 -0.2794)
			(end 0.12065 -0.2794)
			(stroke
				(width 0.1)
				(type default)
			)
			(layer "F.Fab")
		)
		(fp_line
			(start 0.120396 0.2794)
			(end -0.12065 0.2794)
			(stroke
				(width 0.1)
				(type default)
			)
			(layer "F.Fab")
		)
		(fp_line
			(start -0.12065 0.2794)
			(end -0.12065 0.3048)
			(stroke
				(width 0.1)
				(type default)
			)
			(layer "F.Fab")
		)
		(fp_line
			(start 0.67945 0.3048)
			(end 0.120396 0.3048)
			(stroke
				(width 0.1)
				(type default)
			)
			(layer "F.Fab")
		)
		(fp_line
			(start 0.120396 0.3048)
			(end 0.120396 0.2794)
			(stroke
				(width 0.1)
				(type default)
			)
			(layer "F.Fab")
		)
		(fp_line
			(start -0.12065 0.3048)
			(end -0.67945 0.3048)
			(stroke
				(width 0.1)
				(type default)
			)
			(layer "F.Fab")
		)
		(fp_line
			(start -0.67945 0.3048)
			(end -0.67945 -0.305054)
			(stroke
				(width 0.1)
				(type default)
			)
			(layer "F.Fab")
		)
		(pad "1" smd circle
			(at -0.40005 0 90)
			(size 0 0)
			(layers "F.Cu" "F.Mask" "F.Paste")
			(net "P3V3_AUX_BMC_D")
		)
		(pad "2" smd circle
			(at 0.40005 0 90)
			(size 0 0)
			(layers "F.Cu" "F.Mask" "F.Paste")
			(net "GND")
		)
	)
)
